FILE_TYPE = MULTI_PHYS_TABLE;

PART 'EMMITSBURG_REV0P9'

{========================================================================================}
:VALUE                            | PART_TYPE | MATERIAL | PART_NUMBER    = STANDARD | LIFECYCLE     | PART_NUMBER   | JEDEC_TYPE     | DESCRIPTION                           | MANUFTR | MANUF_PN                         | RD_CMPLS_LVL | CMPLS_LVL | FROM_PJ     | CLASS | DIP_SMD | DATA                                   | EE_CHECK_LIST | FP_ECN                  | PSL | CREATOR | STATUS | MSD  | ESD_CDM | ESD_HBM | ESD_MM | PIN_LENGTH_SHORT_PIN | PIN_LENGTH_LONG_PIN | CREATEDAY  ;
{========================================================================================}
 'GFNOCPU04302300-QV2N-MM#99A1WT' | 'SMLF'    | 'IC'     | 'AJ0QV2N0T00'(!) = ''       | ''               | 'AJ0QV2N0T00' |'BGA749_22X23'| 'IC CTRL(749P)EMMITSBURG-QV2N(FCBGA)' | 'INT'   | 'GFNOCPU04302300-QV2N-MM#99A1WT' | ''           | ''        | 'S6X-SANDY' | 'IC'  | ''      | 'INT_emmitsburg-eds-606161-rev0-4.pdf' | ''            | 'Emmitsburg_rev0p9.msg' | ''  | ''      | ''     | 'NA' | 'N/A'   | 'N/A'   | 'N/A'  | '0 MILS'             | '0 MILS'            | '20191211'
 'GFNOCPU04302300-QV2N-MM#99A1WT' | 'SMLF'    | 'EMPTY'  | 'AJ0QV2N0T00'(!) = ''       | ''               | 'AJ0QV2N0T00' |'BGA749_22X23'| 'IC CTRL(749P)EMMITSBURG-QV2N(FCBGA)' | 'INT'   | 'GFNOCPU04302300-QV2N-MM#99A1WT' | ''           | ''        | 'S6X-SANDY' | 'IC'  | ''      | 'INT_emmitsburg-eds-606161-rev0-4.pdf' | ''            | 'Emmitsburg_rev0p9.msg' | ''  | ''      | ''     | 'NA' | 'N/A'   | 'N/A'   | 'N/A'  | '0 MILS'             | '0 MILS'            | '20191211'

END_PART

END.

